(kicad_pcb
	(version 20241229)
	(generator "pcbnew")
	(generator_version "9.0")
	(general
		(thickness 1.294)
		(legacy_teardrops no)
	)
	(paper "A3")
	(title_block
		(title "Kintex 410T devboard")
		(date "2024-04-03")
		(rev "1.1.2")
		(comment 9 "footprints 708-712 of 975")
	)
	(layers
		(0 "F.Cu" mixed)
		(4 "In1.Cu" power)
		(6 "In2.Cu" power)
		(8 "In3.Cu" mixed)
		(10 "In4.Cu" power)
		(12 "In5.Cu" mixed)
		(14 "In6.Cu" power)
		(16 "In7.Cu" mixed)
		(18 "In8.Cu" power)
		(2 "B.Cu" mixed)
		(9 "F.Adhes" user "F.Adhesive")
		(11 "B.Adhes" user "B.Adhesive")
		(13 "F.Paste" user)
		(15 "B.Paste" user)
		(5 "F.SilkS" user "F.Silkscreen")
		(7 "B.SilkS" user "B.Silkscreen")
		(1 "F.Mask" user)
		(3 "B.Mask" user)
		(17 "Dwgs.User" user "User.Drawings")
		(19 "Cmts.User" user "User.Comments")
		(21 "Eco1.User" user "User.Eco1")
		(23 "Eco2.User" user "User.Eco2")
		(25 "Edge.Cuts" user)
		(27 "Margin" user)
		(31 "F.CrtYd" user "F.Courtyard")
		(29 "B.CrtYd" user "B.Courtyard")
		(35 "F.Fab" user)
		(33 "B.Fab" user)
	)
	(footprint "antmicro-footprints:C_0603_1608Metric"
		(layer "B.Cu")
		(at 161.8 147 -90)
		(descr "Capacitor SMD 0603")
		(tags "capacitor 0603")
		(property "Reference" "C166"
			(at 0.175 -1.575 90)
			(layer "B.SilkS")
			(effects
				(font
					(size 0.7 0.7)
					(thickness 0.15)
				)
				(justify left bottom mirror)
			)
		)
		(property "Value" "C_47u_0603"
			(at 0 -1.6 90)
			(layer "B.Fab")
			(effects
				(font
					(size 0.7 0.7)
					(thickness 0.15)
				)
				(justify left bottom mirror)
			)
		)
		(property "Description" "SMD Multilayer Ceramic Capacitor, 47 µF, 6.3 V, 0603 [1608 Metric], ± 20%, X5R, GRM Series"
			(at 0 0 270)
			(layer "F.Fab")
			(hide yes)
			(effects
				(font
					(size 1.27 1.27)
					(thickness 0.15)
				)
			)
		)
		(property "Author" "Antmicro"
			(at 14.8 308.8 0)
			(layer "B.Fab")
			(hide yes)
			(effects
				(font
					(size 1 1)
					(thickness 0.15)
				)
				(justify mirror)
			)
		)
		(property "Dielectric" ""
			(at 14.8 308.8 0)
			(layer "B.Fab")
			(hide yes)
			(effects
				(font
					(size 1 1)
					(thickness 0.15)
				)
				(justify mirror)
			)
		)
		(property "License" "Apache-2.0"
			(at 14.8 308.8 0)
			(layer "B.Fab")
			(hide yes)
			(effects
				(font
					(size 1 1)
					(thickness 0.15)
				)
				(justify mirror)
			)
		)
		(property "MPN" "GRM188R60J476ME15D"
			(at 14.8 308.8 0)
			(layer "B.Fab")
			(hide yes)
			(effects
				(font
					(size 1 1)
					(thickness 0.15)
				)
				(justify mirror)
			)
		)
		(property "Manufacturer" "Murata"
			(at 14.8 308.8 0)
			(layer "B.Fab")
			(hide yes)
			(effects
				(font
					(size 1 1)
					(thickness 0.15)
				)
				(justify mirror)
			)
		)
		(property "Val" "47u"
			(at 14.8 308.8 0)
			(layer "B.Fab")
			(hide yes)
			(effects
				(font
					(size 1 1)
					(thickness 0.15)
				)
				(justify mirror)
			)
		)
		(property "Voltage" ""
			(at 14.8 308.8 0)
			(layer "B.Fab")
			(hide yes)
			(effects
				(font
					(size 1 1)
					(thickness 0.15)
				)
				(justify mirror)
			)
		)
		(sheetname "DRAM + SRAM")
		(sheetfile "ram.kicad_sch")
		(attr smd)
		(fp_line
			(start -0.15 0.4)
			(end 0.15 0.4)
			(stroke
				(width 0.15)
				(type solid)
			)
			(layer "B.SilkS")
		)
		(fp_line
			(start -0.15 -0.4)
			(end 0.15 -0.4)
			(stroke
				(width 0.15)
				(type solid)
			)
			(layer "B.SilkS")
		)
		(fp_rect
			(start -1.25 0.65)
			(end 1.25 -0.65)
			(stroke
				(width 0.05)
				(type solid)
			)
			(fill no)
			(layer "B.CrtYd")
		)
		(fp_rect
			(start -0.8 0.4)
			(end 0.8 -0.4)
			(stroke
				(width 0.15)
				(type solid)
			)
			(fill no)
			(layer "B.Fab")
		)
		(pad "1" smd roundrect
			(at -0.7 0 270)
			(size 0.8 1)
			(layers "B.Cu" "B.Mask" "B.Paste")
			(roundrect_rratio 0.2)
			(net 7 "+0V675_VTT")
			(pintype "passive")
		)
		(pad "2" smd roundrect
			(at 0.7 0 270)
			(size 0.8 1)
			(layers "B.Cu" "B.Mask" "B.Paste")
			(roundrect_rratio 0.2)
			(net 25 "+1V35")
			(pintype "passive")
		)
	)
	(footprint "antmicro-footprints:SOT-23-3"
		(layer "B.Cu")
		(at 162.4 186)
		(property "Reference" "D33"
			(at 0.925 -1.775 180)
			(layer "B.SilkS")
			(effects
				(font
					(size 0.7 0.7)
					(thickness 0.15)
				)
				(justify left bottom mirror)
			)
		)
		(property "Value" "BZX84C5V1-TP"
			(at -1.9 -2.7 180)
			(layer "B.Fab")
			(effects
				(font
					(size 0.7 0.7)
					(thickness 0.15)
				)
				(justify left bottom mirror)
			)
		)
		(property "Description" "Zener Single Diode, 5.1 V, 350 mW, SOT-23, 3 Pins, 150 °C, Surface Mount"
			(at 0 0 0)
			(layer "F.Fab")
			(hide yes)
			(effects
				(font
					(size 1.27 1.27)
					(thickness 0.15)
				)
			)
		)
		(property "Author" "Antmicro"
			(at 0 0 0)
			(layer "B.Fab")
			(hide yes)
			(effects
				(font
					(size 1 1)
					(thickness 0.15)
				)
				(justify mirror)
			)
		)
		(property "License" "Apache-2.0"
			(at 0 0 0)
			(layer "B.Fab")
			(hide yes)
			(effects
				(font
					(size 1 1)
					(thickness 0.15)
				)
				(justify mirror)
			)
		)
		(property "MPN" "BZX84C5V1-TP"
			(at 0 0 0)
			(layer "B.Fab")
			(hide yes)
			(effects
				(font
					(size 1 1)
					(thickness 0.15)
				)
				(justify mirror)
			)
		)
		(property "Manufacturer" "Micro Commercial Components"
			(at 0 0 0)
			(layer "B.Fab")
			(hide yes)
			(effects
				(font
					(size 1 1)
					(thickness 0.15)
				)
				(justify mirror)
			)
		)
		(sheetname "DC-DC Converters")
		(sheetfile "dc-dc.kicad_sch")
		(attr smd)
		(fp_line
			(start -1.45 1.35)
			(end -0.85 1.35)
			(stroke
				(width 0.15)
				(type solid)
			)
			(layer "B.SilkS")
		)
		(fp_line
			(start -0.85 1.35)
			(end -0.7 1.5)
			(stroke
				(width 0.15)
				(type solid)
			)
			(layer "B.SilkS")
		)
		(fp_line
			(start -0.7 -1.5)
			(end -0.7 -1.35)
			(stroke
				(width 0.15)
				(type solid)
			)
			(layer "B.SilkS")
		)
		(fp_line
			(start 0.7 -1.5)
			(end -0.7 -1.5)
			(stroke
				(width 0.15)
				(type solid)
			)
			(layer "B.SilkS")
		)
		(fp_line
			(start 0.7 -0.4)
			(end 0.7 -1.5)
			(stroke
				(width 0.15)
				(type solid)
			)
			(layer "B.SilkS")
		)
		(fp_line
			(start 0.7 0.4)
			(end 0.7 1.5)
			(stroke
				(width 0.15)
				(type solid)
			)
			(layer "B.SilkS")
		)
		(fp_line
			(start 0.7 1.5)
			(end -0.7 1.5)
			(stroke
				(width 0.15)
				(type solid)
			)
			(layer "B.SilkS")
		)
		(fp_line
			(start -1.75 -1.4)
			(end -1.75 -0.5)
			(stroke
				(width 0.05)
				(type solid)
			)
			(layer "B.CrtYd")
		)
		(fp_line
			(start -1.75 -0.5)
			(end -0.85 -0.5)
			(stroke
				(width 0.05)
				(type solid)
			)
			(layer "B.CrtYd")
		)
		(fp_line
			(start -1.75 0.5)
			(end -1.75 1.4)
			(stroke
				(width 0.05)
				(type solid)
			)
			(layer "B.CrtYd")
		)
		(fp_line
			(start -0.9 1.4)
			(end -1.75 1.4)
			(stroke
				(width 0.05)
				(type solid)
			)
			(layer "B.CrtYd")
		)
		(fp_line
			(start -0.9 1.6)
			(end -0.9 1.4)
			(stroke
				(width 0.05)
				(type solid)
			)
			(layer "B.CrtYd")
		)
		(fp_line
			(start -0.9 1.6)
			(end 0.825 1.6)
			(stroke
				(width 0.05)
				(type solid)
			)
			(layer "B.CrtYd")
		)
		(fp_line
			(start -0.85 -1.65)
			(end -0.85 -1.4)
			(stroke
				(width 0.05)
				(type solid)
			)
			(layer "B.CrtYd")
		)
		(fp_line
			(start -0.85 -1.4)
			(end -1.75 -1.4)
			(stroke
				(width 0.05)
				(type solid)
			)
			(layer "B.CrtYd")
		)
		(fp_line
			(start -0.85 -0.5)
			(end -0.85 0.5)
			(stroke
				(width 0.05)
				(type solid)
			)
			(layer "B.CrtYd")
		)
		(fp_line
			(start -0.85 0.5)
			(end -1.75 0.5)
			(stroke
				(width 0.05)
				(type solid)
			)
			(layer "B.CrtYd")
		)
		(fp_line
			(start 0.825 0.45)
			(end 1.75 0.45)
			(stroke
				(width 0.05)
				(type solid)
			)
			(layer "B.CrtYd")
		)
		(fp_line
			(start 0.825 1.6)
			(end 0.825 0.45)
			(stroke
				(width 0.05)
				(type solid)
			)
			(layer "B.CrtYd")
		)
		(fp_line
			(start 0.85 -1.65)
			(end -0.85 -1.65)
			(stroke
				(width 0.05)
				(type solid)
			)
			(layer "B.CrtYd")
		)
		(fp_line
			(start 0.85 -0.45)
			(end 0.85 -1.65)
			(stroke
				(width 0.05)
				(type solid)
			)
			(layer "B.CrtYd")
		)
		(fp_line
			(start 1.75 -0.45)
			(end 0.85 -0.45)
			(stroke
				(width 0.05)
				(type solid)
			)
			(layer "B.CrtYd")
		)
		(fp_line
			(start 1.75 0.45)
			(end 1.75 -0.45)
			(stroke
				(width 0.05)
				(type solid)
			)
			(layer "B.CrtYd")
		)
		(fp_line
			(start -0.712 -1.519)
			(end 0.688 -1.519)
			(stroke
				(width 0.15)
				(type solid)
			)
			(layer "B.Fab")
		)
		(fp_line
			(start -0.712 1.325)
			(end -0.712 -1.523)
			(stroke
				(width 0.15)
				(type solid)
			)
			(layer "B.Fab")
		)
		(fp_line
			(start -0.437 1.526)
			(end -0.712 1.325)
			(stroke
				(width 0.15)
				(type solid)
			)
			(layer "B.Fab")
		)
		(fp_line
			(start -0.437 1.526)
			(end 0.688 1.526)
			(stroke
				(width 0.15)
				(type solid)
			)
			(layer "B.Fab")
		)
		(fp_line
			(start 0.688 -1.519)
			(end 0.688 1.52)
			(stroke
				(width 0.15)
				(type solid)
			)
			(layer "B.Fab")
		)
		(pad "1" smd roundrect
			(at -1.1 0.951)
			(size 1 0.6)
			(layers "B.Cu" "B.Mask" "B.Paste")
			(roundrect_rratio 0.15)
			(net 1 "GND")
			(pinfunction "A")
			(pintype "passive")
		)
		(pad "2" smd roundrect
			(at -1.1 -0.949)
			(size 1 0.6)
			(layers "B.Cu" "B.Mask" "B.Paste")
			(roundrect_rratio 0.15)
			(net 1195 "unconnected-(D33-Pad2)")
			(pinfunction "2")
			(pintype "no_connect")
		)
		(pad "3" smd roundrect
			(at 1.1 0.0005)
			(size 1 0.6)
			(layers "B.Cu" "B.Mask" "B.Paste")
			(roundrect_rratio 0.15)
			(net 797 "/DC-DC Converters/PB_CTRL_OE")
			(pinfunction "C")
			(pintype "passive")
		)
	)
	(footprint "antmicro-footprints:C_0201"
		(layer "B.Cu")
		(at 203.45 126.5 -90)
		(descr "Capacitor SMD 0201")
		(tags "capacitor SMD 0201")
		(property "Reference" "C9"
			(at -30.45 -28.2 90)
			(layer "B.SilkS")
			(effects
				(font
					(size 0.7 0.7)
					(thickness 0.15)
				)
				(justify left bottom mirror)
			)
		)
		(property "Value" "C_4u7_0201"
			(at 0 -1.4 90)
			(layer "B.Fab")
			(effects
				(font
					(size 0.7 0.7)
					(thickness 0.15)
				)
				(justify left bottom mirror)
			)
		)
		(property "Description" "SMD Multilayer Ceramic Capacitor, 4.7 µF, 6.3 V, 0201 [0603 Metric], ± 20%, X5R, GRM Series"
			(at 0 0 270)
			(layer "F.Fab")
			(hide yes)
			(effects
				(font
					(size 1.27 1.27)
					(thickness 0.15)
				)
			)
		)
		(property "Author" "Antmicro"
			(at 76.95 329.95 0)
			(layer "B.Fab")
			(hide yes)
			(effects
				(font
					(size 1 1)
					(thickness 0.15)
				)
				(justify mirror)
			)
		)
		(property "Dielectric" ""
			(at 76.95 329.95 0)
			(layer "B.Fab")
			(hide yes)
			(effects
				(font
					(size 1 1)
					(thickness 0.15)
				)
				(justify mirror)
			)
		)
		(property "License" "Apache-2.0"
			(at 76.95 329.95 0)
			(layer "B.Fab")
			(hide yes)
			(effects
				(font
					(size 1 1)
					(thickness 0.15)
				)
				(justify mirror)
			)
		)
		(property "MPN" "GRM035R60J475ME15D"
			(at 76.95 329.95 0)
			(layer "B.Fab")
			(hide yes)
			(effects
				(font
					(size 1 1)
					(thickness 0.15)
				)
				(justify mirror)
			)
		)
		(property "Manufacturer" "Murata"
			(at 76.95 329.95 0)
			(layer "B.Fab")
			(hide yes)
			(effects
				(font
					(size 1 1)
					(thickness 0.15)
				)
				(justify mirror)
			)
		)
		(property "Val" "4u7"
			(at 76.95 329.95 0)
			(layer "B.Fab")
			(hide yes)
			(effects
				(font
					(size 1 1)
					(thickness 0.15)
				)
				(justify mirror)
			)
		)
		(property "Voltage" ""
			(at 76.95 329.95 0)
			(layer "B.Fab")
			(hide yes)
			(effects
				(font
					(size 1 1)
					(thickness 0.15)
				)
				(justify mirror)
			)
		)
		(sheetname "FPGA supply")
		(sheetfile "fpga-supply.kicad_sch")
		(attr smd)
		(fp_rect
			(start -0.7 0.35)
			(end 0.7 -0.35)
			(stroke
				(width 0.05)
				(type default)
			)
			(fill no)
			(layer "B.CrtYd")
		)
		(fp_rect
			(start 0.3 -0.15)
			(end -0.301 0.149)
			(stroke
				(width 0.15)
				(type solid)
			)
			(fill no)
			(layer "B.Fab")
		)
		(pad "" smd roundrect
			(at -0.349 0.002 270)
			(size 0.318 0.36)
			(layers "B.Paste")
			(roundrect_rratio 0.25)
		)
		(pad "" smd roundrect
			(at 0.341 0.002 270)
			(size 0.318 0.36)
			(layers "B.Paste")
			(roundrect_rratio 0.25)
		)
		(pad "1" smd roundrect
			(at -0.321 0.002 270)
			(size 0.46 0.4)
			(layers "B.Cu" "B.Mask")
			(roundrect_rratio 0.25)
			(net 1 "GND")
			(pintype "passive")
		)
		(pad "2" smd roundrect
			(at 0.32 0.002 270)
			(size 0.46 0.4)
			(layers "B.Cu" "B.Mask")
			(roundrect_rratio 0.25)
			(net 650 "+1V0")
			(pintype "passive")
		)
	)
	(footprint "antmicro-footprints:R_0402_1005Metric"
		(layer "B.Cu")
		(at 253.801 166.8 -90)
		(descr "Resistor SMD 0402")
		(tags "resistor SMD 0402")
		(property "Reference" "R250"
			(at -0.925 1.551 90)
			(layer "B.SilkS")
			(effects
				(font
					(size 0.7 0.7)
					(thickness 0.15)
				)
				(justify left bottom mirror)
			)
		)
		(property "Value" "R_49R9_0402"
			(at 0 -1.4 90)
			(layer "B.Fab")
			(effects
				(font
					(size 0.7 0.7)
					(thickness 0.15)
				)
				(justify left bottom mirror)
			)
		)
		(property "Description" "SMD Chip Resistor, 49.9 ohm, ± 1%, 62.5 mW, 0402 [1005 Metric], Thick Film, General Purpose"
			(at 0 0 270)
			(layer "F.Fab")
			(hide yes)
			(effects
				(font
					(size 1.27 1.27)
					(thickness 0.15)
				)
			)
		)
		(property "Author" "Antmicro"
			(at 87.001 420.601 0)
			(layer "B.Fab")
			(hide yes)
			(effects
				(font
					(size 1 1)
					(thickness 0.15)
				)
				(justify mirror)
			)
		)
		(property "License" "Apache-2.0"
			(at 87.001 420.601 0)
			(layer "B.Fab")
			(hide yes)
			(effects
				(font
					(size 1 1)
					(thickness 0.15)
				)
				(justify mirror)
			)
		)
		(property "MPN" "CR0402-FX-49R9GLF"
			(at 87.001 420.601 0)
			(layer "B.Fab")
			(hide yes)
			(effects
				(font
					(size 1 1)
					(thickness 0.15)
				)
				(justify mirror)
			)
		)
		(property "Manufacturer" "Bourns"
			(at 87.001 420.601 0)
			(layer "B.Fab")
			(hide yes)
			(effects
				(font
					(size 1 1)
					(thickness 0.15)
				)
				(justify mirror)
			)
		)
		(property "Tolerance" "1%"
			(at 87.001 420.601 0)
			(layer "B.Fab")
			(hide yes)
			(effects
				(font
					(size 1 1)
					(thickness 0.15)
				)
				(justify mirror)
			)
		)
		(property "Val" "49R9"
			(at 87.001 420.601 0)
			(layer "B.Fab")
			(hide yes)
			(effects
				(font
					(size 1 1)
					(thickness 0.15)
				)
				(justify mirror)
			)
		)
		(sheetname "HDMI + Ethernet")
		(sheetfile "hdmi-ethernet.kicad_sch")
		(attr smd)
		(fp_rect
			(start -0.925 0.47)
			(end 0.925 -0.47)
			(stroke
				(width 0.05)
				(type default)
			)
			(fill no)
			(layer "B.CrtYd")
		)
		(fp_rect
			(start -0.5 0.25)
			(end 0.5 -0.25)
			(stroke
				(width 0.15)
				(type solid)
			)
			(fill no)
			(layer "B.Fab")
		)
		(pad "1" smd roundrect
			(at -0.48 0 270)
			(size 0.59 0.64)
			(layers "B.Cu" "B.Mask" "B.Paste")
			(roundrect_rratio 0.25)
			(net 729 "/HDMI + Ethernet/ETH2_N")
			(pintype "passive")
		)
		(pad "2" smd roundrect
			(at 0.48 0 270)
			(size 0.59 0.64)
			(layers "B.Cu" "B.Mask" "B.Paste")
			(roundrect_rratio 0.25)
			(net 721 "/HDMI + Ethernet/ETH_3V3")
			(pintype "passive")
		)
	)
	(footprint "antmicro-footprints:C_0603_1608Metric"
		(layer "B.Cu")
		(at 197.69 147.25)
		(descr "Capacitor SMD 0603")
		(tags "capacitor 0603")
		(property "Reference" "C107"
			(at 1.435 1.4 180)
			(layer "B.SilkS")
			(effects
				(font
					(size 0.7 0.7)
					(thickness 0.15)
				)
				(justify left bottom mirror)
			)
		)
		(property "Value" "C_47u_0603"
			(at 0 -1.6 180)
			(layer "B.Fab")
			(effects
				(font
					(size 0.7 0.7)
					(thickness 0.15)
				)
				(justify left bottom mirror)
			)
		)
		(property "Description" "SMD Multilayer Ceramic Capacitor, 47 µF, 6.3 V, 0603 [1608 Metric], ± 20%, X5R, GRM Series"
			(at 0 0 0)
			(layer "F.Fab")
			(hide yes)
			(effects
				(font
					(size 1.27 1.27)
					(thickness 0.15)
				)
			)
		)
		(property "Author" "Antmicro"
			(at 0 0 0)
			(layer "B.Fab")
			(hide yes)
			(effects
				(font
					(size 1 1)
					(thickness 0.15)
				)
				(justify mirror)
			)
		)
		(property "Dielectric" ""
			(at 0 0 0)
			(layer "B.Fab")
			(hide yes)
			(effects
				(font
					(size 1 1)
					(thickness 0.15)
				)
				(justify mirror)
			)
		)
		(property "License" "Apache-2.0"
			(at 0 0 0)
			(layer "B.Fab")
			(hide yes)
			(effects
				(font
					(size 1 1)
					(thickness 0.15)
				)
				(justify mirror)
			)
		)
		(property "MPN" "GRM188R60J476ME15D"
			(at 0 0 0)
			(layer "B.Fab")
			(hide yes)
			(effects
				(font
					(size 1 1)
					(thickness 0.15)
				)
				(justify mirror)
			)
		)
		(property "Manufacturer" "Murata"
			(at 0 0 0)
			(layer "B.Fab")
			(hide yes)
			(effects
				(font
					(size 1 1)
					(thickness 0.15)
				)
				(justify mirror)
			)
		)
		(property "Val" "47u"
			(at 0 0 0)
			(layer "B.Fab")
			(hide yes)
			(effects
				(font
					(size 1 1)
					(thickness 0.15)
				)
				(justify mirror)
			)
		)
		(property "Voltage" ""
			(at 0 0 0)
			(layer "B.Fab")
			(hide yes)
			(effects
				(font
					(size 1 1)
					(thickness 0.15)
				)
				(justify mirror)
			)
		)
		(sheetname "FPGA Bank 18 & 32")
		(sheetfile "fpga-bank-18-32.kicad_sch")
		(attr smd)
		(fp_line
			(start -0.15 -0.4)
			(end 0.15 -0.4)
			(stroke
				(width 0.15)
				(type solid)
			)
			(layer "B.SilkS")
		)
		(fp_line
			(start -0.15 0.4)
			(end 0.15 0.4)
			(stroke
				(width 0.15)
				(type solid)
			)
			(layer "B.SilkS")
		)
		(fp_rect
			(start -1.25 0.65)
			(end 1.25 -0.65)
			(stroke
				(width 0.05)
				(type solid)
			)
			(fill no)
			(layer "B.CrtYd")
		)
		(fp_rect
			(start -0.8 0.4)
			(end 0.8 -0.4)
			(stroke
				(width 0.15)
				(type solid)
			)
			(fill no)
			(layer "B.Fab")
		)
		(pad "1" smd roundrect
			(at -0.7 0)
			(size 0.8 1)
			(layers "B.Cu" "B.Mask" "B.Paste")
			(roundrect_rratio 0.2)
			(net 26 "+1V8")
			(pintype "passive")
		)
		(pad "2" smd roundrect
			(at 0.7 0)
			(size 0.8 1)
			(layers "B.Cu" "B.Mask" "B.Paste")
			(roundrect_rratio 0.2)
			(net 1 "GND")
			(pintype "passive")
		)
	)
)
